# TIMECARD (Time Appliance Project (Time Card)) — schematic netlist excerpt (pin names and nets, part order shuffled) for the footprints in the layout excerpt that follows; sources: Cadence DE-HDL packaged netlist, KiCad conversion of R4006-B0001-02_R01.brd

R457  RESISTOR  4.7KOHM 1%  pkg SMC_0402R_H016  page 24 : \1\ = XP3R3V_FPGA ; \2\ = MUX2_SEL
C211  CAPACITOR  0.1UF 10V 10%  pkg SMC_0402R_H022  page 14 : \1\ = XP3R3V_FPGA ; \2\ = SG

(kicad_pcb
	(version 20260206)
	(generator "pcbnew")
	(generator_version "10.0")
	(general
		(thickness 1.6)
		(legacy_teardrops no)
	)
	(paper "A4")
	(title_block
		(title "timecard-production-celestica-r4006 — R4006-B0001-02_R01.brd")
		(comment 1 "Time Appliance Project (Time Card) / footprints 928-929 of 1113")
	)
	(layers
		(0 "F.Cu" signal "TOP")
		(4 "In1.Cu" signal "L02_GND1")
		(6 "In2.Cu" signal "L03_SIG1")
		(8 "In3.Cu" signal "L04_GND2")
		(10 "In4.Cu" signal "L05_VCC1")
		(12 "In5.Cu" signal "L06_VCC2")
		(14 "In6.Cu" signal "L07_GND3")
		(16 "In7.Cu" signal "L08_SIG2")
		(18 "In8.Cu" signal "L09_GND4")
		(2 "B.Cu" signal "BOTTOM")
		(9 "F.Adhes" user "F.Adhesive")
		(11 "B.Adhes" user "B.Adhesive")
		(13 "F.Paste" user "Package Geometry/Pastemask Top")
		(15 "B.Paste" user "Package Geometry/Pastemask Bottom")
		(5 "F.SilkS" user "Ref Des/Silkscreen Top")
		(7 "B.SilkS" user "Ref Des/Silkscreen Bottom")
		(1 "F.Mask" user "Board Geometry/Soldermask Top")
		(3 "B.Mask" user "Board Geometry/Soldermask Bottom")
		(17 "Dwgs.User" user "User.Drawings")
		(19 "Cmts.User" user "User.Comments")
		(21 "Eco1.User" user "User.Eco1")
		(23 "Eco2.User" user "User.Eco2")
		(25 "Edge.Cuts" user "Board Geometry/Outline")
		(27 "Margin" user)
		(31 "F.CrtYd" user "Package Geometry/Place Bound Top")
		(29 "B.CrtYd" user "Package Geometry/Place Bound Bottom")
		(35 "F.Fab" user "Ref Des/Assembly Top")
		(33 "B.Fab" user "Ref Des/Assembly Bottom")
	)
	(footprint ""
		(layer "B.Cu")
		(at 100.347018 -50.823114)
		(property "Reference" "C211"
			(at -1.287018 1.070864 0)
			(unlocked yes)
			(layer "B.SilkS")
			(effects
				(font
					(size 0.635 0.4064)
					(thickness 0.1524)
				)
				(justify mirror)
			)
		)
		(property "Value" "VAL*"
			(at 0 3.718306 0)
			(unlocked yes)
			(layer "B.Fab")
			(hide yes)
			(effects
				(font
					(size 0.7874 0.5842)
					(thickness 0.127)
				)
				(justify mirror)
			)
		)
		(property "Device Type" "CAPACITOR-G105-0B104-CK,0.1UF,A"
			(at 0 1.432306 0)
			(unlocked yes)
			(layer "B.Fab")
			(hide yes)
			(effects
				(font
					(size 0.7874 0.5842)
					(thickness 0.127)
				)
				(justify mirror)
			)
		)
		(property "User Part Number" "PARTNUM*"
			(at 0 2.575306 0)
			(unlocked yes)
			(layer "Cmts.User")
			(hide yes)
			(effects
				(font
					(size 0.7874 0.5842)
					(thickness 0.127)
				)
				(justify mirror)
			)
		)
		(property "Tolerance" "TOL*"
			(at 0 4.861306 0)
			(unlocked yes)
			(layer "Cmts.User")
			(hide yes)
			(effects
				(font
					(size 0.7874 0.5842)
					(thickness 0.127)
				)
				(justify mirror)
			)
		)
		(duplicate_pad_numbers_are_jumpers no)
		(fp_line
			(start -0.970026 -0.4699)
			(end -0.970026 0.4699)
			(stroke
				(width 0.1)
				(type default)
			)
			(layer "B.SilkS")
		)
		(fp_line
			(start -0.970026 0.4699)
			(end 0.970026 0.4699)
			(stroke
				(width 0.1)
				(type default)
			)
			(layer "B.SilkS")
		)
		(fp_line
			(start 0.970026 -0.4699)
			(end -0.970026 -0.4699)
			(stroke
				(width 0.1)
				(type default)
			)
			(layer "B.SilkS")
		)
		(fp_line
			(start 0.970026 0.4699)
			(end 0.970026 -0.4699)
			(stroke
				(width 0.1)
				(type default)
			)
			(layer "B.SilkS")
		)
		(fp_poly
			(pts
				(xy 0.970026 0.4699) (xy -0.970026 0.4699) (xy -0.970026 -0.4699) (xy 0.970026 -0.4699)
			)
			(stroke
				(width 0)
				(type default)
			)
			(fill no)
			(layer "B.CrtYd")
		)
		(fp_line
			(start -0.508 -0.3048)
			(end -0.508 0.3048)
			(stroke
				(width 0.1)
				(type default)
			)
			(layer "B.Fab")
		)
		(fp_line
			(start -0.508 0.3048)
			(end 0.508 0.3048)
			(stroke
				(width 0.1)
				(type default)
			)
			(layer "B.Fab")
		)
		(fp_line
			(start 0.508 -0.3048)
			(end -0.508 -0.3048)
			(stroke
				(width 0.1)
				(type default)
			)
			(layer "B.Fab")
		)
		(fp_line
			(start 0.508 0.3048)
			(end 0.508 -0.3048)
			(stroke
				(width 0.1)
				(type default)
			)
			(layer "B.Fab")
		)
		(pad "1" smd circle
			(at 0.500126 0 180)
			(size 0.635 0.635)
			(layers "B.Cu" "B.Mask" "B.Paste")
			(net "XP3R3V_FPGA")
		)
		(pad "2" smd circle
			(at -0.500126 0 180)
			(size 0.635 0.635)
			(layers "B.Cu" "B.Mask" "B.Paste")
			(net "SG")
		)
	)
	(footprint ""
		(layer "B.Cu")
		(at 101.4476 -83.5914 180)
		(property "Reference" "R457"
			(at -0.1524 1.07823 0)
			(unlocked yes)
			(layer "B.SilkS")
			(effects
				(font
					(size 0.7874 0.5842)
					(thickness 0.1524)
				)
				(justify mirror)
			)
		)
		(property "Value" "VAL*"
			(at -0.02032 2.13233 180)
			(unlocked yes)
			(layer "B.Fab")
			(hide yes)
			(effects
				(font
					(size 0.7874 0.5842)
					(thickness 0.1524)
				)
				(justify mirror)
			)
		)
		(property "Tolerance" "TOL*"
			(at -0.044704 3.05435 180)
			(unlocked yes)
			(layer "Cmts.User")
			(hide yes)
			(effects
				(font
					(size 0.7874 0.5842)
					(thickness 0.1524)
				)
				(justify mirror)
			)
		)
		(property "User Part Number" "PARTNUM*"
			(at -0.02032 4.024884 180)
			(unlocked yes)
			(layer "Cmts.User")
			(hide yes)
			(effects
				(font
					(size 0.7874 0.5842)
					(thickness 0.1524)
				)
				(justify mirror)
			)
		)
		(property "Device Type" "RESISTOR-G155-14701-01,4.7KOHMA"
			(at -0.008382 1.210564 180)
			(unlocked yes)
			(layer "B.Fab")
			(hide yes)
			(effects
				(font
					(size 0.7874 0.5842)
					(thickness 0.1524)
				)
				(justify mirror)
			)
		)
		(duplicate_pad_numbers_are_jumpers no)
		(fp_line
			(start 1.143 0.5588)
			(end -1.143 0.5588)
			(stroke
				(width 0.1)
				(type default)
			)
			(layer "B.SilkS")
		)
		(fp_line
			(start 1.143 -0.5588)
			(end 1.143 0.5588)
			(stroke
				(width 0.1)
				(type default)
			)
			(layer "B.SilkS")
		)
		(fp_line
			(start -1.143 0.5588)
			(end -1.143 -0.5588)
			(stroke
				(width 0.1)
				(type default)
			)
			(layer "B.SilkS")
		)
		(fp_line
			(start -1.143 -0.5588)
			(end 1.143 -0.5588)
			(stroke
				(width 0.1)
				(type default)
			)
			(layer "B.SilkS")
		)
		(fp_poly
			(pts
				(xy 1.143 0.5588) (xy -1.143 0.5588) (xy -1.143 -0.5588) (xy 1.143 -0.5588)
			)
			(stroke
				(width 0)
				(type default)
			)
			(fill no)
			(layer "B.CrtYd")
		)
		(fp_line
			(start 0.508 0.3048)
			(end -0.508 0.3048)
			(stroke
				(width 0.1)
				(type default)
			)
			(layer "B.Fab")
		)
		(fp_line
			(start 0.508 -0.3048)
			(end 0.508 0.3048)
			(stroke
				(width 0.1)
				(type default)
			)
			(layer "B.Fab")
		)
		(fp_line
			(start -0.508 0.3048)
			(end -0.508 -0.3048)
			(stroke
				(width 0.1)
				(type default)
			)
			(layer "B.Fab")
		)
		(fp_line
			(start -0.508 -0.3048)
			(end 0.508 -0.3048)
			(stroke
				(width 0.1)
				(type default)
			)
			(layer "B.Fab")
		)
		(pad "1" smd rect
			(at 0.5334 0)
			(size 0.7112 0.6096)
			(layers "B.Cu" "B.Mask" "B.Paste")
			(net "XP3R3V_FPGA")
		)
		(pad "2" smd rect
			(at -0.5334 0)
			(size 0.7112 0.6096)
			(layers "B.Cu" "B.Mask" "B.Paste")
			(net "MUX2_SEL")
		)
		(zone
			(layer "B.Cu")
			(hatch none 0.5)
			(connect_pads
				(clearance 0)
			)
			(min_thickness 0.25)
			(keepout
				(tracks not_allowed)
				(vias allowed)
				(pads allowed)
				(copperpour not_allowed)
				(footprints allowed)
			)
			(placement
				(enabled no)
				(sheetname "")
			)
			(fill
				(thermal_gap 0.5)
				(thermal_bridge_width 0.5)
				(island_removal_mode 0)
			)
			(polygon
				(pts
					(xy 101.3714 -83.8962) (xy 101.3714 -83.2866) (xy 101.5238 -83.2866) (xy 101.5238 -83.8962)
				)
			)
		)
		(zone
			(layer "B.Cu")
			(hatch none 0.5)
			(connect_pads
				(clearance 0)
			)
			(min_thickness 0.25)
			(keepout
				(tracks allowed)
				(vias not_allowed)
				(pads allowed)
				(copperpour not_allowed)
				(footprints allowed)
			)
			(placement
				(enabled no)
				(sheetname "")
			)
			(fill
				(thermal_gap 0.5)
				(thermal_bridge_width 0.5)
				(island_removal_mode 0)
			)
			(polygon
				(pts
					(xy 101.3714 -83.8962) (xy 101.3714 -83.2866) (xy 101.5238 -83.2866) (xy 101.5238 -83.8962)
				)
			)
		)
	)
)
